# T6G (Grand Teton) — schematic netlist excerpt (pin names and nets, part order shuffled) for the footprints in the layout excerpt that follows; sources: Cadence DE-HDL packaged netlist, KiCad conversion of 04192023_DAF0TMB3IC0_F0TG_MB_C_brd_V02_OCP.brd

R139  Q_RES  0 5% EMPTY  pkg 0402LF  page 161 : A = I3C_MUX_CPU0_VIO ; B = PVDD18_S5_P0
C259  Q_CAP  22UF 4V 20% X6S  pkg C0402  page 323 : A = P0V9_CPU1_RT0_2A ; B = GND

(kicad_pcb
	(version 20260206)
	(generator "pcbnew")
	(generator_version "10.0")
	(general
		(thickness 1.6)
		(legacy_teardrops no)
	)
	(paper "A4")
	(title_block
		(title "04192023_DAF0TMB3IC0_F0TG_MB_C_brd_V02_OCP.brd")
		(comment 1 "Grand Teton / footprints 5391-5392 of 8354")
	)
	(layers
		(0 "F.Cu" signal "TOP")
		(4 "In1.Cu" signal "GND")
		(6 "In2.Cu" signal "IN1")
		(8 "In3.Cu" signal "GND1")
		(10 "In4.Cu" signal "IN2")
		(12 "In5.Cu" signal "GND2")
		(14 "In6.Cu" signal "IN3")
		(16 "In7.Cu" signal "GND3")
		(18 "In8.Cu" signal "VCC")
		(20 "In9.Cu" signal "VCC1")
		(22 "In10.Cu" signal "GND4")
		(24 "In11.Cu" signal "IN4")
		(26 "In12.Cu" signal "GND5")
		(28 "In13.Cu" signal "IN5")
		(30 "In14.Cu" signal "GND6")
		(32 "In15.Cu" signal "IN6")
		(34 "In16.Cu" signal "GND7")
		(2 "B.Cu" signal "BOTTOM")
		(9 "F.Adhes" user "F.Adhesive")
		(11 "B.Adhes" user "B.Adhesive")
		(13 "F.Paste" user "Package Geometry/Pastemask Top")
		(15 "B.Paste" user "Package Geometry/Pastemask Bottom")
		(5 "F.SilkS" user "Ref Des/Silkscreen Top")
		(7 "B.SilkS" user "Ref Des/Silkscreen Bottom")
		(1 "F.Mask" user "Board Geometry/Soldermask Top")
		(3 "B.Mask" user "Board Geometry/Soldermask Bottom")
		(17 "Dwgs.User" user "User.Drawings")
		(19 "Cmts.User" user "User.Comments")
		(21 "Eco1.User" user "User.Eco1")
		(23 "Eco2.User" user "User.Eco2")
		(25 "Edge.Cuts" user "Board Geometry/Outline")
		(27 "Margin" user)
		(31 "F.CrtYd" user "Package Geometry/Place Bound Top")
		(29 "B.CrtYd" user "Package Geometry/Place Bound Bottom")
		(35 "F.Fab" user "Ref Des/Assembly Top")
		(33 "B.Fab" user "Ref Des/Assembly Bottom")
	)
	(footprint ""
		(layer "B.Cu")
		(at 48.591216 -390.560052 90)
		(property "Reference" "C259"
			(at 0 0 90)
			(layer "B.SilkS")
			(hide yes)
			(effects
				(font
					(size 1.27 1.27)
				)
				(justify mirror)
			)
		)
		(property "Value" ""
			(at 0 0 90)
			(layer "B.Fab")
			(effects
				(font
					(size 1.27 1.27)
				)
				(justify mirror)
			)
		)
		(duplicate_pad_numbers_are_jumpers no)
		(fp_line
			(start 0.7874 -0.4064)
			(end -0.7874 -0.4064)
			(stroke
				(width 0.1524)
				(type default)
			)
			(layer "B.SilkS")
		)
		(fp_line
			(start -0.7874 -0.4064)
			(end -0.7874 0.4064)
			(stroke
				(width 0.1524)
				(type default)
			)
			(layer "B.SilkS")
		)
		(fp_line
			(start 0.7874 0.4064)
			(end 0.7874 -0.4064)
			(stroke
				(width 0.1524)
				(type default)
			)
			(layer "B.SilkS")
		)
		(fp_line
			(start -0.7874 0.4064)
			(end 0.7874 0.4064)
			(stroke
				(width 0.1524)
				(type default)
			)
			(layer "B.SilkS")
		)
		(fp_line
			(start 0.67945 -0.305054)
			(end 0.12065 -0.305054)
			(stroke
				(width 0.1)
				(type default)
			)
			(layer "B.Fab")
		)
		(fp_line
			(start 0.12065 -0.305054)
			(end 0.12065 -0.2794)
			(stroke
				(width 0.1)
				(type default)
			)
			(layer "B.Fab")
		)
		(fp_line
			(start -0.12065 -0.3048)
			(end -0.67945 -0.3048)
			(stroke
				(width 0.1)
				(type default)
			)
			(layer "B.Fab")
		)
		(fp_line
			(start -0.67945 -0.3048)
			(end -0.67945 0.3048)
			(stroke
				(width 0.1)
				(type default)
			)
			(layer "B.Fab")
		)
		(fp_line
			(start 0.12065 -0.2794)
			(end -0.12065 -0.2794)
			(stroke
				(width 0.1)
				(type default)
			)
			(layer "B.Fab")
		)
		(fp_line
			(start -0.12065 -0.2794)
			(end -0.12065 -0.3048)
			(stroke
				(width 0.1)
				(type default)
			)
			(layer "B.Fab")
		)
		(fp_line
			(start 0.12065 0.2794)
			(end 0.12065 0.3048)
			(stroke
				(width 0.1)
				(type default)
			)
			(layer "B.Fab")
		)
		(fp_line
			(start -0.120396 0.2794)
			(end 0.12065 0.2794)
			(stroke
				(width 0.1)
				(type default)
			)
			(layer "B.Fab")
		)
		(fp_line
			(start 0.67945 0.3048)
			(end 0.67945 -0.305054)
			(stroke
				(width 0.1)
				(type default)
			)
			(layer "B.Fab")
		)
		(fp_line
			(start 0.12065 0.3048)
			(end 0.67945 0.3048)
			(stroke
				(width 0.1)
				(type default)
			)
			(layer "B.Fab")
		)
		(fp_line
			(start -0.120396 0.3048)
			(end -0.120396 0.2794)
			(stroke
				(width 0.1)
				(type default)
			)
			(layer "B.Fab")
		)
		(fp_line
			(start -0.67945 0.3048)
			(end -0.120396 0.3048)
			(stroke
				(width 0.1)
				(type default)
			)
			(layer "B.Fab")
		)
		(pad "1" smd circle
			(at 0.40005 0 270)
			(size 0 0)
			(layers "B.Cu" "B.Mask" "B.Paste")
			(net "P0V9_CPU1_RT0_2A")
		)
		(pad "2" smd circle
			(at -0.40005 0 270)
			(size 0 0)
			(layers "B.Cu" "B.Mask" "B.Paste")
			(net "GND")
		)
	)
	(footprint ""
		(layer "B.Cu")
		(at 231.902 -232.156 90)
		(property "Reference" "R139"
			(at 0 0 90)
			(layer "B.SilkS")
			(hide yes)
			(effects
				(font
					(size 1.27 1.27)
				)
				(justify mirror)
			)
		)
		(property "Value" ""
			(at 0 0 90)
			(layer "B.Fab")
			(effects
				(font
					(size 1.27 1.27)
				)
				(justify mirror)
			)
		)
		(duplicate_pad_numbers_are_jumpers no)
		(fp_line
			(start 0.7874 -0.4064)
			(end -0.7874 -0.4064)
			(stroke
				(width 0.1524)
				(type default)
			)
			(layer "B.SilkS")
		)
		(fp_line
			(start -0.7874 -0.4064)
			(end -0.7874 0.4064)
			(stroke
				(width 0.1524)
				(type default)
			)
			(layer "B.SilkS")
		)
		(fp_line
			(start 0.7874 0.4064)
			(end 0.7874 -0.4064)
			(stroke
				(width 0.1524)
				(type default)
			)
			(layer "B.SilkS")
		)
		(fp_line
			(start -0.7874 0.4064)
			(end 0.7874 0.4064)
			(stroke
				(width 0.1524)
				(type default)
			)
			(layer "B.SilkS")
		)
		(fp_line
			(start 0.67945 -0.305054)
			(end 0.12065 -0.305054)
			(stroke
				(width 0.1)
				(type default)
			)
			(layer "B.Fab")
		)
		(fp_line
			(start 0.12065 -0.305054)
			(end 0.12065 -0.2794)
			(stroke
				(width 0.1)
				(type default)
			)
			(layer "B.Fab")
		)
		(fp_line
			(start -0.12065 -0.3048)
			(end -0.67945 -0.3048)
			(stroke
				(width 0.1)
				(type default)
			)
			(layer "B.Fab")
		)
		(fp_line
			(start -0.67945 -0.3048)
			(end -0.67945 0.3048)
			(stroke
				(width 0.1)
				(type default)
			)
			(layer "B.Fab")
		)
		(fp_line
			(start 0.12065 -0.2794)
			(end -0.12065 -0.2794)
			(stroke
				(width 0.1)
				(type default)
			)
			(layer "B.Fab")
		)
		(fp_line
			(start -0.12065 -0.2794)
			(end -0.12065 -0.3048)
			(stroke
				(width 0.1)
				(type default)
			)
			(layer "B.Fab")
		)
		(fp_line
			(start 0.12065 0.2794)
			(end 0.12065 0.3048)
			(stroke
				(width 0.1)
				(type default)
			)
			(layer "B.Fab")
		)
		(fp_line
			(start -0.120396 0.2794)
			(end 0.12065 0.2794)
			(stroke
				(width 0.1)
				(type default)
			)
			(layer "B.Fab")
		)
		(fp_line
			(start 0.67945 0.3048)
			(end 0.67945 -0.305054)
			(stroke
				(width 0.1)
				(type default)
			)
			(layer "B.Fab")
		)
		(fp_line
			(start 0.12065 0.3048)
			(end 0.67945 0.3048)
			(stroke
				(width 0.1)
				(type default)
			)
			(layer "B.Fab")
		)
		(fp_line
			(start -0.120396 0.3048)
			(end -0.120396 0.2794)
			(stroke
				(width 0.1)
				(type default)
			)
			(layer "B.Fab")
		)
		(fp_line
			(start -0.67945 0.3048)
			(end -0.120396 0.3048)
			(stroke
				(width 0.1)
				(type default)
			)
			(layer "B.Fab")
		)
		(pad "1" smd circle
			(at 0.40005 0 270)
			(size 0 0)
			(layers "B.Cu" "B.Mask" "B.Paste")
			(net "I3C_MUX_CPU0_VIO")
		)
		(pad "2" smd circle
			(at -0.40005 0 270)
			(size 0 0)
			(layers "B.Cu" "B.Mask" "B.Paste")
			(net "PVDD18_S5_P0")
		)
	)
)
